(kicad_pcb
	(version 20260206)
	(generator "pcbnew")
	(generator_version "10.0")
	(general
		(thickness 1.6)
		(legacy_teardrops no)
	)
	(paper "A4")
	(title_block
		(title "v2-pdb — ms_pdb_v2.brd")
		(comment 1 "Open CloudServer (Microsoft) / footprints 83-92 of 348")
	)
	(layers
		(0 "F.Cu" signal "TOP")
		(4 "In1.Cu" signal "GND")
		(6 "In2.Cu" signal "IN1")
		(8 "In3.Cu" signal "VCC")
		(10 "In4.Cu" signal "VCC1")
		(12 "In5.Cu" signal "IN2")
		(14 "In6.Cu" signal "GND1")
		(2 "B.Cu" signal "BOTTOM")
		(9 "F.Adhes" user "F.Adhesive")
		(11 "B.Adhes" user "B.Adhesive")
		(13 "F.Paste" user "Package Geometry/Pastemask Top")
		(15 "B.Paste" user "Package Geometry/Pastemask Bottom")
		(5 "F.SilkS" user "Ref Des/Silkscreen Top")
		(7 "B.SilkS" user "Ref Des/Silkscreen Bottom")
		(1 "F.Mask" user "Board Geometry/Soldermask Top")
		(3 "B.Mask" user "Board Geometry/Soldermask Bottom")
		(17 "Dwgs.User" user "User.Drawings")
		(19 "Cmts.User" user "User.Comments")
		(21 "Eco1.User" user "User.Eco1")
		(23 "Eco2.User" user "User.Eco2")
		(25 "Edge.Cuts" user "Board Geometry/Outline")
		(27 "Margin" user)
		(31 "F.CrtYd" user "Package Geometry/Place Bound Top")
		(29 "B.CrtYd" user "Package Geometry/Place Bound Bottom")
		(35 "F.Fab" user "Ref Des/Assembly Top")
		(33 "B.Fab" user "Ref Des/Assembly Bottom")
	)
	(footprint ""
		(layer "F.Cu")
		(at 67.187064 -127.633476 90)
		(property "Reference" "C28"
			(at 1.21158 -0.185674 90)
			(unlocked yes)
			(layer "F.SilkS")
			(effects
				(font
					(size 0.7874 0.5842)
					(thickness 0.1524)
				)
				(justify left)
			)
		)
		(property "Value" ""
			(at 0 0 90)
			(layer "F.Fab")
			(effects
				(font
					(size 1.27 1.27)
				)
			)
		)
		(duplicate_pad_numbers_are_jumpers no)
		(fp_line
			(start 0.7874 -0.4064)
			(end 0.7874 0.4064)
			(stroke
				(width 0.1524)
				(type default)
			)
			(layer "F.SilkS")
		)
		(fp_line
			(start -0.7874 -0.4064)
			(end 0.7874 -0.4064)
			(stroke
				(width 0.1524)
				(type default)
			)
			(layer "F.SilkS")
		)
		(fp_line
			(start 0 0.381)
			(end 0 -0.381)
			(stroke
				(width 0.1524)
				(type default)
			)
			(layer "F.SilkS")
		)
		(fp_line
			(start 0.7874 0.4064)
			(end -0.7874 0.4064)
			(stroke
				(width 0.1524)
				(type default)
			)
			(layer "F.SilkS")
		)
		(fp_line
			(start -0.7874 0.4064)
			(end -0.7874 -0.4064)
			(stroke
				(width 0.1524)
				(type default)
			)
			(layer "F.SilkS")
		)
		(fp_poly
			(pts
				(xy -0.5334 0.254) (xy -0.635 0.254) (xy -0.635 0.2286) (xy -0.635 -0.254) (xy -0.5334 -0.254) (xy -0.5334 -0.2794)
				(xy 0.5334 -0.2794) (xy 0.5334 -0.254) (xy 0.635 -0.254) (xy 0.635 0.254) (xy 0.5334 0.254) (xy 0.5334 0.2794)
				(xy -0.508 0.2794) (xy -0.5334 0.2794)
			)
			(stroke
				(width 0)
				(type default)
			)
			(fill no)
			(layer "F.CrtYd")
		)
		(pad "1" smd rect
			(at 0.40005 0 90)
			(size 0.4572 0.508)
			(layers "F.Cu" "F.Mask" "F.Paste")
			(net "P12V")
		)
		(pad "2" smd rect
			(at -0.40005 0 90)
			(size 0.4572 0.508)
			(layers "F.Cu" "F.Mask" "F.Paste")
			(net "GND")
		)
	)
	(footprint ""
		(layer "F.Cu")
		(at 72.284082 -439.03646 90)
		(property "Reference" "C75"
			(at 1.327912 0.132334 90)
			(unlocked yes)
			(layer "F.SilkS")
			(effects
				(font
					(size 0.7874 0.5842)
					(thickness 0.1524)
				)
				(justify left)
			)
		)
		(property "Value" ""
			(at 0 0 90)
			(layer "F.Fab")
			(effects
				(font
					(size 1.27 1.27)
				)
			)
		)
		(duplicate_pad_numbers_are_jumpers no)
		(fp_line
			(start 0.7874 -0.4064)
			(end 0.7874 0.4064)
			(stroke
				(width 0.1524)
				(type default)
			)
			(layer "F.SilkS")
		)
		(fp_line
			(start -0.7874 -0.4064)
			(end 0.7874 -0.4064)
			(stroke
				(width 0.1524)
				(type default)
			)
			(layer "F.SilkS")
		)
		(fp_line
			(start 0 0.381)
			(end 0 -0.381)
			(stroke
				(width 0.1524)
				(type default)
			)
			(layer "F.SilkS")
		)
		(fp_line
			(start 0.7874 0.4064)
			(end -0.7874 0.4064)
			(stroke
				(width 0.1524)
				(type default)
			)
			(layer "F.SilkS")
		)
		(fp_line
			(start -0.7874 0.4064)
			(end -0.7874 -0.4064)
			(stroke
				(width 0.1524)
				(type default)
			)
			(layer "F.SilkS")
		)
		(fp_poly
			(pts
				(xy -0.5334 0.254) (xy -0.635 0.254) (xy -0.635 0.2286) (xy -0.635 -0.254) (xy -0.5334 -0.254) (xy -0.5334 -0.2794)
				(xy 0.5334 -0.2794) (xy 0.5334 -0.254) (xy 0.635 -0.254) (xy 0.635 0.254) (xy 0.5334 0.254) (xy 0.5334 0.2794)
				(xy -0.508 0.2794) (xy -0.5334 0.2794)
			)
			(stroke
				(width 0)
				(type default)
			)
			(fill no)
			(layer "F.CrtYd")
		)
		(pad "1" smd rect
			(at 0.40005 0 90)
			(size 0.4572 0.508)
			(layers "F.Cu" "F.Mask" "F.Paste")
			(net "P12V")
		)
		(pad "2" smd rect
			(at -0.40005 0 90)
			(size 0.4572 0.508)
			(layers "F.Cu" "F.Mask" "F.Paste")
			(net "GND")
		)
	)
	(footprint ""
		(layer "F.Cu")
		(at 26.001726 -101.689408)
		(property "Reference" "R135"
			(at -4.183888 -0.051562 0)
			(unlocked yes)
			(layer "F.SilkS")
			(effects
				(font
					(size 0.7874 0.5842)
					(thickness 0.1524)
				)
				(justify left)
			)
		)
		(property "Value" ""
			(at 0 0 0)
			(layer "F.Fab")
			(effects
				(font
					(size 1.27 1.27)
				)
			)
		)
		(duplicate_pad_numbers_are_jumpers no)
		(fp_line
			(start -0.7874 -0.4064)
			(end 0.7874 -0.4064)
			(stroke
				(width 0.1524)
				(type default)
			)
			(layer "F.SilkS")
		)
		(fp_line
			(start -0.7874 0.4064)
			(end -0.7874 -0.4064)
			(stroke
				(width 0.1524)
				(type default)
			)
			(layer "F.SilkS")
		)
		(fp_line
			(start 0.7874 -0.4064)
			(end 0.7874 0.4064)
			(stroke
				(width 0.1524)
				(type default)
			)
			(layer "F.SilkS")
		)
		(fp_line
			(start 0.7874 0.4064)
			(end -0.7874 0.4064)
			(stroke
				(width 0.1524)
				(type default)
			)
			(layer "F.SilkS")
		)
		(fp_poly
			(pts
				(xy -0.508 0.2794) (xy -0.508 0.2286) (xy -0.635 0.2286) (xy -0.635 -0.254) (xy -0.5334 -0.254)
				(xy -0.5334 -0.2794) (xy 0.5334 -0.2794) (xy 0.5334 -0.254) (xy 0.635 -0.254) (xy 0.635 0.254) (xy 0.5334 0.254)
				(xy 0.5334 0.2794)
			)
			(stroke
				(width 0)
				(type default)
			)
			(fill no)
			(layer "F.CrtYd")
		)
		(pad "1" smd rect
			(at 0.40005 0)
			(size 0.4572 0.508)
			(layers "F.Cu" "F.Mask" "F.Paste")
			(net "PSU2_CSAHRE")
		)
		(pad "2" smd rect
			(at -0.40005 0)
			(size 0.4572 0.508)
			(layers "F.Cu" "F.Mask" "F.Paste")
			(net "PSU_CSAHRE")
		)
	)
	(footprint ""
		(layer "F.Cu")
		(at 45.911516 -260.355588 180)
		(property "Reference" "R103"
			(at 4.696206 0.233172 0)
			(unlocked yes)
			(layer "F.SilkS")
			(effects
				(font
					(size 0.7874 0.5842)
					(thickness 0.1524)
				)
				(justify left)
			)
		)
		(property "Value" ""
			(at 0 0 180)
			(layer "F.Fab")
			(effects
				(font
					(size 1.27 1.27)
				)
			)
		)
		(duplicate_pad_numbers_are_jumpers no)
		(fp_line
			(start 0.7874 0.4064)
			(end -0.7874 0.4064)
			(stroke
				(width 0.1524)
				(type default)
			)
			(layer "F.SilkS")
		)
		(fp_line
			(start 0.7874 -0.4064)
			(end 0.7874 0.4064)
			(stroke
				(width 0.1524)
				(type default)
			)
			(layer "F.SilkS")
		)
		(fp_line
			(start -0.7874 0.4064)
			(end -0.7874 -0.4064)
			(stroke
				(width 0.1524)
				(type default)
			)
			(layer "F.SilkS")
		)
		(fp_line
			(start -0.7874 -0.4064)
			(end 0.7874 -0.4064)
			(stroke
				(width 0.1524)
				(type default)
			)
			(layer "F.SilkS")
		)
		(fp_poly
			(pts
				(xy -0.508 0.2794) (xy -0.508 0.2286) (xy -0.635 0.2286) (xy -0.635 -0.254) (xy -0.5334 -0.254)
				(xy -0.5334 -0.2794) (xy 0.5334 -0.2794) (xy 0.5334 -0.254) (xy 0.635 -0.254) (xy 0.635 0.254) (xy 0.5334 0.254)
				(xy 0.5334 0.2794)
			)
			(stroke
				(width 0)
				(type default)
			)
			(fill no)
			(layer "F.CrtYd")
		)
		(pad "1" smd rect
			(at 0.40005 0 180)
			(size 0.4572 0.508)
			(layers "F.Cu" "F.Mask" "F.Paste")
			(net "PSU5_REMOTE_R_N")
		)
		(pad "2" smd rect
			(at -0.40005 0 180)
			(size 0.4572 0.508)
			(layers "F.Cu" "F.Mask" "F.Paste")
			(net "GND")
		)
	)
	(footprint ""
		(layer "F.Cu")
		(at 73.963276 -241.518694 -90)
		(property "Reference" "C37"
			(at 0.73406 -3.745992 90)
			(unlocked yes)
			(layer "F.SilkS")
			(effects
				(font
					(size 0.7874 0.5842)
					(thickness 0.1524)
				)
				(justify left)
			)
		)
		(property "Value" ""
			(at 0 0 270)
			(layer "F.Fab")
			(effects
				(font
					(size 1.27 1.27)
				)
			)
		)
		(duplicate_pad_numbers_are_jumpers no)
		(fp_line
			(start -0.7874 0.4064)
			(end -0.7874 -0.4064)
			(stroke
				(width 0.1524)
				(type default)
			)
			(layer "F.SilkS")
		)
		(fp_line
			(start 0.7874 0.4064)
			(end -0.7874 0.4064)
			(stroke
				(width 0.1524)
				(type default)
			)
			(layer "F.SilkS")
		)
		(fp_line
			(start 0 0.381)
			(end 0 -0.381)
			(stroke
				(width 0.1524)
				(type default)
			)
			(layer "F.SilkS")
		)
		(fp_line
			(start -0.7874 -0.4064)
			(end 0.7874 -0.4064)
			(stroke
				(width 0.1524)
				(type default)
			)
			(layer "F.SilkS")
		)
		(fp_line
			(start 0.7874 -0.4064)
			(end 0.7874 0.4064)
			(stroke
				(width 0.1524)
				(type default)
			)
			(layer "F.SilkS")
		)
		(fp_poly
			(pts
				(xy -0.5334 0.254) (xy -0.635 0.254) (xy -0.635 0.2286) (xy -0.635 -0.254) (xy -0.5334 -0.254) (xy -0.5334 -0.2794)
				(xy 0.5334 -0.2794) (xy 0.5334 -0.254) (xy 0.635 -0.254) (xy 0.635 0.254) (xy 0.5334 0.254) (xy 0.5334 0.2794)
				(xy -0.508 0.2794) (xy -0.5334 0.2794)
			)
			(stroke
				(width 0)
				(type default)
			)
			(fill no)
			(layer "F.CrtYd")
		)
		(pad "1" smd rect
			(at 0.40005 0 270)
			(size 0.4572 0.508)
			(layers "F.Cu" "F.Mask" "F.Paste")
			(net "P12V")
		)
		(pad "2" smd rect
			(at -0.40005 0 270)
			(size 0.4572 0.508)
			(layers "F.Cu" "F.Mask" "F.Paste")
			(net "GND")
		)
	)
	(footprint ""
		(layer "F.Cu")
		(at 70.678548 -483.48138 90)
		(property "Reference" "C83"
			(at -4.10845 0.070104 90)
			(unlocked yes)
			(layer "F.SilkS")
			(effects
				(font
					(size 0.7874 0.5842)
					(thickness 0.1524)
				)
				(justify left)
			)
		)
		(property "Value" ""
			(at 0 0 90)
			(layer "F.Fab")
			(effects
				(font
					(size 1.27 1.27)
				)
			)
		)
		(duplicate_pad_numbers_are_jumpers no)
		(fp_line
			(start 0.7874 -0.4064)
			(end 0.7874 0.4064)
			(stroke
				(width 0.1524)
				(type default)
			)
			(layer "F.SilkS")
		)
		(fp_line
			(start -0.7874 -0.4064)
			(end 0.7874 -0.4064)
			(stroke
				(width 0.1524)
				(type default)
			)
			(layer "F.SilkS")
		)
		(fp_line
			(start 0 0.381)
			(end 0 -0.381)
			(stroke
				(width 0.1524)
				(type default)
			)
			(layer "F.SilkS")
		)
		(fp_line
			(start 0.7874 0.4064)
			(end -0.7874 0.4064)
			(stroke
				(width 0.1524)
				(type default)
			)
			(layer "F.SilkS")
		)
		(fp_line
			(start -0.7874 0.4064)
			(end -0.7874 -0.4064)
			(stroke
				(width 0.1524)
				(type default)
			)
			(layer "F.SilkS")
		)
		(fp_poly
			(pts
				(xy -0.5334 0.254) (xy -0.635 0.254) (xy -0.635 0.2286) (xy -0.635 -0.254) (xy -0.5334 -0.254) (xy -0.5334 -0.2794)
				(xy 0.5334 -0.2794) (xy 0.5334 -0.254) (xy 0.635 -0.254) (xy 0.635 0.254) (xy 0.5334 0.254) (xy 0.5334 0.2794)
				(xy -0.508 0.2794) (xy -0.5334 0.2794)
			)
			(stroke
				(width 0)
				(type default)
			)
			(fill no)
			(layer "F.CrtYd")
		)
		(pad "1" smd rect
			(at 0.40005 0 90)
			(size 0.4572 0.508)
			(layers "F.Cu" "F.Mask" "F.Paste")
			(net "P12V")
		)
		(pad "2" smd rect
			(at -0.40005 0 90)
			(size 0.4572 0.508)
			(layers "F.Cu" "F.Mask" "F.Paste")
			(net "GND")
		)
	)
	(footprint ""
		(layer "F.Cu")
		(at 26.068274 -185.521092)
		(property "Reference" "R70"
			(at -3.997198 0.128524 0)
			(unlocked yes)
			(layer "F.SilkS")
			(effects
				(font
					(size 0.7874 0.5842)
					(thickness 0.1524)
				)
				(justify left)
			)
		)
		(property "Value" ""
			(at 0 0 0)
			(layer "F.Fab")
			(effects
				(font
					(size 1.27 1.27)
				)
			)
		)
		(duplicate_pad_numbers_are_jumpers no)
		(fp_line
			(start -0.7874 -0.4064)
			(end 0.7874 -0.4064)
			(stroke
				(width 0.1524)
				(type default)
			)
			(layer "F.SilkS")
		)
		(fp_line
			(start -0.7874 0.4064)
			(end -0.7874 -0.4064)
			(stroke
				(width 0.1524)
				(type default)
			)
			(layer "F.SilkS")
		)
		(fp_line
			(start 0.7874 -0.4064)
			(end 0.7874 0.4064)
			(stroke
				(width 0.1524)
				(type default)
			)
			(layer "F.SilkS")
		)
		(fp_line
			(start 0.7874 0.4064)
			(end -0.7874 0.4064)
			(stroke
				(width 0.1524)
				(type default)
			)
			(layer "F.SilkS")
		)
		(fp_poly
			(pts
				(xy -0.508 0.2794) (xy -0.508 0.2286) (xy -0.635 0.2286) (xy -0.635 -0.254) (xy -0.5334 -0.254)
				(xy -0.5334 -0.2794) (xy 0.5334 -0.2794) (xy 0.5334 -0.254) (xy 0.635 -0.254) (xy 0.635 0.254) (xy 0.5334 0.254)
				(xy 0.5334 0.2794)
			)
			(stroke
				(width 0)
				(type default)
			)
			(fill no)
			(layer "F.CrtYd")
		)
		(pad "1" smd rect
			(at 0.40005 0)
			(size 0.4572 0.508)
			(layers "F.Cu" "F.Mask" "F.Paste")
			(net "PSU3_PS_KILL")
		)
		(pad "2" smd rect
			(at -0.40005 0)
			(size 0.4572 0.508)
			(layers "F.Cu" "F.Mask" "F.Paste")
			(net "P12V_STBY")
		)
	)
	(footprint ""
		(layer "F.Cu")
		(at 39.97325 -192.216278 180)
		(property "Reference" "R10"
			(at -1.626616 -0.081026 0)
			(unlocked yes)
			(layer "F.SilkS")
			(effects
				(font
					(size 0.7874 0.5842)
					(thickness 0.1524)
				)
				(justify left)
			)
		)
		(property "Value" ""
			(at 0 0 180)
			(layer "F.Fab")
			(effects
				(font
					(size 1.27 1.27)
				)
			)
		)
		(duplicate_pad_numbers_are_jumpers no)
		(fp_line
			(start 0.7874 0.4064)
			(end -0.7874 0.4064)
			(stroke
				(width 0.1524)
				(type default)
			)
			(layer "F.SilkS")
		)
		(fp_line
			(start 0.7874 -0.4064)
			(end 0.7874 0.4064)
			(stroke
				(width 0.1524)
				(type default)
			)
			(layer "F.SilkS")
		)
		(fp_line
			(start -0.7874 0.4064)
			(end -0.7874 -0.4064)
			(stroke
				(width 0.1524)
				(type default)
			)
			(layer "F.SilkS")
		)
		(fp_line
			(start -0.7874 -0.4064)
			(end 0.7874 -0.4064)
			(stroke
				(width 0.1524)
				(type default)
			)
			(layer "F.SilkS")
		)
		(fp_poly
			(pts
				(xy -0.508 0.2794) (xy -0.508 0.2286) (xy -0.635 0.2286) (xy -0.635 -0.254) (xy -0.5334 -0.254)
				(xy -0.5334 -0.2794) (xy 0.5334 -0.2794) (xy 0.5334 -0.254) (xy 0.635 -0.254) (xy 0.635 0.254) (xy 0.5334 0.254)
				(xy 0.5334 0.2794)
			)
			(stroke
				(width 0)
				(type default)
			)
			(fill no)
			(layer "F.CrtYd")
		)
		(pad "1" smd rect
			(at 0.40005 0 180)
			(size 0.4572 0.508)
			(layers "F.Cu" "F.Mask" "F.Paste")
			(net "PSU3_RETURN")
		)
		(pad "2" smd rect
			(at -0.40005 0 180)
			(size 0.4572 0.508)
			(layers "F.Cu" "F.Mask" "F.Paste")
			(net "GND")
		)
	)
	(footprint ""
		(layer "F.Cu")
		(at 46.385734 -244.518434 180)
		(property "Reference" "R91"
			(at 4.322064 -0.051816 0)
			(unlocked yes)
			(layer "F.SilkS")
			(effects
				(font
					(size 0.7874 0.5842)
					(thickness 0.1524)
				)
				(justify left)
			)
		)
		(property "Value" ""
			(at 0 0 180)
			(layer "F.Fab")
			(effects
				(font
					(size 1.27 1.27)
				)
			)
		)
		(duplicate_pad_numbers_are_jumpers no)
		(fp_line
			(start 0.7874 0.4064)
			(end -0.7874 0.4064)
			(stroke
				(width 0.1524)
				(type default)
			)
			(layer "F.SilkS")
		)
		(fp_line
			(start 0.7874 -0.4064)
			(end 0.7874 0.4064)
			(stroke
				(width 0.1524)
				(type default)
			)
			(layer "F.SilkS")
		)
		(fp_line
			(start -0.7874 0.4064)
			(end -0.7874 -0.4064)
			(stroke
				(width 0.1524)
				(type default)
			)
			(layer "F.SilkS")
		)
		(fp_line
			(start -0.7874 -0.4064)
			(end 0.7874 -0.4064)
			(stroke
				(width 0.1524)
				(type default)
			)
			(layer "F.SilkS")
		)
		(fp_poly
			(pts
				(xy -0.508 0.2794) (xy -0.508 0.2286) (xy -0.635 0.2286) (xy -0.635 -0.254) (xy -0.5334 -0.254)
				(xy -0.5334 -0.2794) (xy 0.5334 -0.2794) (xy 0.5334 -0.254) (xy 0.635 -0.254) (xy 0.635 0.254) (xy 0.5334 0.254)
				(xy 0.5334 0.2794)
			)
			(stroke
				(width 0)
				(type default)
			)
			(fill no)
			(layer "F.CrtYd")
		)
		(pad "1" smd rect
			(at 0.40005 0 180)
			(size 0.4572 0.508)
			(layers "F.Cu" "F.Mask" "F.Paste")
			(net "PSU2_REMOTE_R_N")
		)
		(pad "2" smd rect
			(at -0.40005 0 180)
			(size 0.4572 0.508)
			(layers "F.Cu" "F.Mask" "F.Paste")
			(net "GND")
		)
	)
	(footprint ""
		(layer "F.Cu")
		(at 69.982334 -374.411748 -90)
		(property "Reference" "C58"
			(at -2.675128 0.148844 90)
			(unlocked yes)
			(layer "F.SilkS")
			(effects
				(font
					(size 0.7874 0.5842)
					(thickness 0.1524)
				)
				(justify left)
			)
		)
		(property "Value" ""
			(at 0 0 270)
			(layer "F.Fab")
			(effects
				(font
					(size 1.27 1.27)
				)
			)
		)
		(duplicate_pad_numbers_are_jumpers no)
		(fp_line
			(start -0.7874 0.4064)
			(end -0.7874 -0.4064)
			(stroke
				(width 0.1524)
				(type default)
			)
			(layer "F.SilkS")
		)
		(fp_line
			(start 0.7874 0.4064)
			(end -0.7874 0.4064)
			(stroke
				(width 0.1524)
				(type default)
			)
			(layer "F.SilkS")
		)
		(fp_line
			(start 0 0.381)
			(end 0 -0.381)
			(stroke
				(width 0.1524)
				(type default)
			)
			(layer "F.SilkS")
		)
		(fp_line
			(start -0.7874 -0.4064)
			(end 0.7874 -0.4064)
			(stroke
				(width 0.1524)
				(type default)
			)
			(layer "F.SilkS")
		)
		(fp_line
			(start 0.7874 -0.4064)
			(end 0.7874 0.4064)
			(stroke
				(width 0.1524)
				(type default)
			)
			(layer "F.SilkS")
		)
		(fp_poly
			(pts
				(xy -0.5334 0.254) (xy -0.635 0.254) (xy -0.635 0.2286) (xy -0.635 -0.254) (xy -0.5334 -0.254) (xy -0.5334 -0.2794)
				(xy 0.5334 -0.2794) (xy 0.5334 -0.254) (xy 0.635 -0.254) (xy 0.635 0.254) (xy 0.5334 0.254) (xy 0.5334 0.2794)
				(xy -0.508 0.2794) (xy -0.5334 0.2794)
			)
			(stroke
				(width 0)
				(type default)
			)
			(fill no)
			(layer "F.CrtYd")
		)
		(pad "1" smd rect
			(at 0.40005 0 270)
			(size 0.4572 0.508)
			(layers "F.Cu" "F.Mask" "F.Paste")
			(net "P12V")
		)
		(pad "2" smd rect
			(at -0.40005 0 270)
			(size 0.4572 0.508)
			(layers "F.Cu" "F.Mask" "F.Paste")
			(net "GND")
		)
	)
)
